# Kria K26 Devboard — KiCad project settings (.kicad_pro: net classes, design rules, text variables)
{
  "board": {
    "3dviewports": [],
    "design_settings": {
      "defaults": {
        "board_outline_line_width": 0.049999999999999996,
        "copper_line_width": 0.19999999999999998,
        "copper_text_italic": false,
        "copper_text_size_h": 1.5,
        "copper_text_size_v": 1.5,
        "copper_text_thickness": 0.3,
        "copper_text_upright": false,
        "courtyard_line_width": 0.049999999999999996,
        "dimension_precision": 4,
        "dimension_units": 3,
        "dimensions": {
          "arrow_length": 1270000,
          "extension_offset": 500000,
          "keep_text_aligned": true,
          "suppress_zeroes": false,
          "text_position": 0,
          "units_format": 1
        },
        "fab_line_width": 0.09999999999999999,
        "fab_text_italic": false,
        "fab_text_size_h": 1.0,
        "fab_text_size_v": 1.0,
        "fab_text_thickness": 0.15,
        "fab_text_upright": false,
        "other_line_width": 0.09999999999999999,
        "other_text_italic": false,
        "other_text_size_h": 1.0,
        "other_text_size_v": 1.0,
        "other_text_thickness": 0.15,
        "other_text_upright": false,
        "pads": {
          "drill": 4.45,
          "height": 6.0,
          "width": 6.0
        },
        "silk_line_width": 0.12,
        "silk_text_italic": false,
        "silk_text_size_h": 1.0,
        "silk_text_size_v": 1.0,
        "silk_text_thickness": 0.15,
        "silk_text_upright": false,
        "zones": {
          "45_degree_only": false,
          "min_clearance": 0.5
        }
      },
      "diff_pair_dimensions": [
        {
          "gap": 0.0,
          "via_gap": 0.0,
          "width": 0.0
        }
      ],
      "drc_exclusions": [],
      "meta": {
        "filename": "board_design_settings.json",
        "version": 2
      },
      "rule_severities": {
        "annular_width": "error",
        "clearance": "error",
        "connection_width": "warning",
        "copper_edge_clearance": "error",
        "copper_sliver": "warning",
        "courtyards_overlap": "warning",
        "diff_pair_gap_out_of_range": "error",
        "diff_pair_uncoupled_length_too_long": "error",
        "drill_out_of_range": "error",
        "duplicate_footprints": "warning",
        "extra_footprint": "warning",
        "footprint": "error",
        "footprint_type_mismatch": "ignore",
        "hole_clearance": "error",
        "hole_near_hole": "error",
        "invalid_outline": "error",
        "isolated_copper": "warning",
        "item_on_disabled_layer": "error",
        "items_not_allowed": "error",
        "length_out_of_range": "error",
        "lib_footprint_issues": "ignore",
        "lib_footprint_mismatch": "ignore",
        "malformed_courtyard": "warning",
        "microvia_drill_out_of_range": "error",
        "missing_courtyard": "ignore",
        "missing_footprint": "warning",
        "net_conflict": "warning",
        "npth_inside_courtyard": "ignore",
        "padstack": "error",
        "pth_inside_courtyard": "ignore",
        "shorting_items": "error",
        "silk_edge_clearance": "warning",
        "silk_over_copper": "ignore",
        "silk_overlap": "ignore",
        "skew_out_of_range": "error",
        "solder_mask_bridge": "error",
        "starved_thermal": "error",
        "text_height": "warning",
        "text_thickness": "warning",
        "through_hole_pad_without_hole": "error",
        "too_many_vias": "error",
        "track_dangling": "warning",
        "track_width": "error",
        "tracks_crossing": "error",
        "unconnected_items": "error",
        "unresolved_variable": "error",
        "via_dangling": "warning",
        "zones_intersect": "error"
      },
      "rule_severitieslegacy_courtyards_overlap": false,
      "rule_severitieslegacy_no_courtyard_defined": false,
      "rules": {
        "allow_blind_buried_vias": false,
        "allow_microvias": false,
        "max_error": 0.005,
        "min_clearance": 0.09999999999999999,
        "min_connection": 0.0,
        "min_copper_edge_clearance": 0.049999999999999996,
        "min_hole_clearance": 0.15,
        "min_hole_to_hole": 0.25,
        "min_microvia_diameter": 0.19999999999999998,
        "min_microvia_drill": 0.09999999999999999,
        "min_resolved_spokes": 2,
        "min_silk_clearance": 0.0,
        "min_text_height": 0.6,
        "min_text_thickness": 0.08,
        "min_through_hole_diameter": 0.09999999999999999,
        "min_track_width": 0.09999999999999999,
        "min_via_annular_width": 0.049999999999999996,
        "min_via_diameter": 0.39999999999999997,
        "solder_mask_to_copper_clearance": 0.0,
        "use_height_for_length_calcs": true
      },
      "teardrop_options": [
        {
          "td_allow_use_two_tracks": true,
          "td_curve_segcount": 5,
          "td_on_pad_in_zone": false,
          "td_onpadsmd": true,
          "td_onroundshapesonly": false,
          "td_ontrackend": false,
          "td_onviapad": true
        }
      ],
      "teardrop_parameters": [
        {
          "td_curve_segcount": 0,
          "td_height_ratio": 1.0,
          "td_length_ratio": 0.5,
          "td_maxheight": 2.0,
          "td_maxlen": 1.0,
          "td_target_name": "td_round_shape",
          "td_width_to_size_filter_ratio": 0.9
        },
        {
          "td_curve_segcount": 0,
          "td_height_ratio": 1.0,
          "td_length_ratio": 0.5,
          "td_maxheight": 2.0,
          "td_maxlen": 1.0,
          "td_target_name": "td_rect_shape",
          "td_width_to_size_filter_ratio": 0.9
        },
        {
          "td_curve_segcount": 0,
          "td_height_ratio": 1.0,
          "td_length_ratio": 0.5,
          "td_maxheight": 2.0,
          "td_maxlen": 1.0,
          "td_target_name": "td_track_end",
          "td_width_to_size_filter_ratio": 0.9
        }
      ],
      "track_widths": [
        0.0,
        0.107,
        0.109,
        0.178,
        0.182,
        0.2,
        0.4,
        1.0
      ],
      "via_dimensions": [
        {
          "diameter": 0.0,
          "drill": 0.0
        },
        {
          "diameter": 0.45,
          "drill": 0.1
        },
        {
          "diameter": 0.5,
          "drill": 0.15
        },
        {
          "diameter": 0.6,
          "drill": 0.25
        },
        {
          "diameter": 0.8,
          "drill": 0.4
        }
      ],
      "zones_allow_external_fillets": false,
      "zones_use_no_outline": true
    },
    "layer_presets": [],
    "viewports": []
  },
  "boards": [],
  "cvpcb": {
    "equivalence_files": []
  },
  "erc": {
    "erc_exclusions": [],
    "meta": {
      "version": 0
    },
    "pin_map": [
      [
        0,
        0,
        0,
        0,
        0,
        0,
        1,
        0,
        0,
        0,
        0,
        2
      ],
      [
        0,
        2,
        0,
        1,
        0,
        0,
        1,
        0,
        2,
        2,
        2,
        2
      ],
      [
        0,
        0,
        0,
        0,
        0,
        0,
        1,
        0,
        1,
        0,
        1,
        2
      ],
      [
        0,
        1,
        0,
        0,
        0,
        0,
        1,
        1,
        2,
        1,
        1,
        2
      ],
      [
        0,
        0,
        0,
        0,
        0,
        0,
        1,
        0,
        0,
        0,
        0,
        2
      ],
      [
        0,
        0,
        0,
        0,
        0,
        0,
        0,
        0,
        0,
        0,
        0,
        2
      ],
      [
        1,
        1,
        1,
        1,
        1,
        0,
        1,
        1,
        1,
        1,
        1,
        2
      ],
      [
        0,
        0,
        0,
        1,
        0,
        0,
        1,
        0,
        0,
        0,
        0,
        2
      ],
      [
        0,
        2,
        1,
        2,
        0,
        0,
        1,
        0,
        2,
        2,
        2,
        2
      ],
      [
        0,
        2,
        0,
        1,
        0,
        0,
        1,
        0,
        2,
        0,
        0,
        2
      ],
      [
        0,
        2,
        1,
        1,
        0,
        0,
        1,
        0,
        2,
        0,
        0,
        2
      ],
      [
        2,
        2,
        2,
        2,
        2,
        2,
        2,
        2,
        2,
        2,
        2,
        2
      ]
    ],
    "rule_severities": {
      "bus_definition_conflict": "error",
      "bus_entry_needed": "error",
      "bus_to_bus_conflict": "error",
      "bus_to_net_conflict": "error",
      "conflicting_netclasses": "error",
      "different_unit_footprint": "error",
      "different_unit_net": "error",
      "duplicate_reference": "error",
      "duplicate_sheet_names": "error",
      "endpoint_off_grid": "warning",
      "extra_units": "error",
      "global_label_dangling": "warning",
      "hier_label_mismatch": "error",
      "label_dangling": "error",
      "lib_symbol_issues": "warning",
      "missing_bidi_pin": "warning",
      "missing_input_pin": "warning",
      "missing_power_pin": "error",
      "missing_unit": "warning",
      "multiple_net_names": "warning",
      "net_not_bus_member": "warning",
      "no_connect_connected": "ignore",
      "no_connect_dangling": "warning",
      "pin_not_connected": "error",
      "pin_not_driven": "error",
      "pin_to_pin": "ignore",
      "power_pin_not_driven": "error",
      "similar_labels": "warning",
      "simulation_model_issue": "ignore",
      "unannotated": "error",
      "unit_value_mismatch": "error",
      "unresolved_variable": "error",
      "wire_dangling": "error"
    }
  },
  "libraries": {
    "pinned_footprint_libs": [],
    "pinned_symbol_libs": []
  },
  "meta": {
    "filename": "kria-k26-devboard.kicad_pro",
    "version": 1
  },
  "net_settings": {
    "classes": [
      {
        "bus_width": 12,
        "clearance": 0.1,
        "diff_pair_gap": 0.25,
        "diff_pair_via_gap": 0.25,
        "diff_pair_width": 0.2,
        "line_style": 0,
        "microvia_diameter": 0.3,
        "microvia_drill": 0.1,
        "name": "Default",
        "pcb_color": "rgba(0, 0, 0, 0.000)",
        "schematic_color": "rgba(0, 0, 0, 0.000)",
        "track_width": 0.109,
        "via_diameter": 0.4,
        "via_drill": 0.15,
        "wire_width": 6
      },
      {
        "bus_width": 12,
        "clearance": 0.1,
        "diff_pair_gap": 0.386,
        "diff_pair_via_gap": 0.25,
        "diff_pair_width": 0.178,
        "line_style": 0,
        "microvia_diameter": 0.3,
        "microvia_drill": 0.1,
        "name": "Clocks_100Ohm",
        "pcb_color": "rgba(0, 0, 0, 0.000)",
        "schematic_color": "rgba(0, 0, 0, 0.000)",
        "track_width": 0.109,
        "via_diameter": 0.4,
        "via_drill": 0.1,
        "wire_width": 6
      },
      {
        "bus_width": 12,
        "clearance": 0.1,
        "diff_pair_gap": 0.25,
        "diff_pair_via_gap": 0.25,
        "diff_pair_width": 0.2,
        "line_style": 0,
        "microvia_diameter": 0.3,
        "microvia_drill": 0.1,
        "name": "Supply",
        "pcb_color": "rgba(0, 0, 0, 0.000)",
        "schematic_color": "rgba(0, 0, 0, 0.000)",
        "track_width": 0.2,
        "via_diameter": 0.4,
        "via_drill": 0.15,
        "wire_width": 6
      },
      {
        "bus_width": 12,
        "clearance": 0.1,
        "diff_pair_gap": 0.146,
        "diff_pair_via_gap": 0.25,
        "diff_pair_width": 0.109,
        "line_style": 0,
        "microvia_diameter": 0.4,
        "microvia_drill": 0.1,
        "name": "impedance_ctrl",
        "pcb_color": "rgba(0, 0, 0, 0.000)",
        "schematic_color": "rgba(0, 0, 0, 0.000)",
        "track_width": 0.182,
        "via_diameter": 0.4,
        "via_drill": 0.1,
        "wire_width": 6
      }
    ],
    "meta": {
      "version": 3
    },
    "net_colors": null,
    "netclass_assignments": null,
    "netclass_patterns": [
      {
        "netclass": "Clocks_100Ohm",
        "pattern": "/Clock distribution/CLK_100M_N"
      },
      {
        "netclass": "Clocks_100Ohm",
        "pattern": "/Clock distribution/CLK_100M_P"
      },
      {
        "netclass": "Clocks_100Ohm",
        "pattern": "/Clock distribution/GTR_REFCLK0_C2M_N"
      },
      {
        "netclass": "Clocks_100Ohm",
        "pattern": "/Clock distribution/GTR_REFCLK0_C2M_P"
      },
      {
        "netclass": "Clocks_100Ohm",
        "pattern": "/Clock distribution/GTR_REFCLK1_C2M_N"
      },
      {
        "netclass": "Clocks_100Ohm",
        "pattern": "/Clock distribution/GTR_REFCLK1_C2M_P"
      },
      {
        "netclass": "Clocks_100Ohm",
        "pattern": "/Clock distribution/GTR_REFCLK2_C2M_N"
      },
      {
        "netclass": "Clocks_100Ohm",
        "pattern": "/Clock distribution/GTR_REFCLK2_C2M_P"
      },
      {
        "netclass": "Clocks_100Ohm",
        "pattern": "/Clock distribution/GTR_REFCLK3_C2M_N"
      },
      {
        "netclass": "Clocks_100Ohm",
        "pattern": "/Clock distribution/GTR_REFCLK3_C2M_P"
      },
      {
        "netclass": "Clocks_100Ohm",
        "pattern": "/Clock distribution/GTR_REFCLK3_N"
      },
      {
        "netclass": "Clocks_100Ohm",
        "pattern": "/Clock distribution/GTR_REFCLK3_P"
      },
      {
        "netclass": "Clocks_100Ohm",
        "pattern": "/Display Port/DP_AUX_C_N"
      },
      {
        "netclass": "Clocks_100Ohm",
        "pattern": "/Display Port/DP_AUX_C_P"
      },
      {
        "netclass": "Clocks_100Ohm",
        "pattern": "/Display Port/DP_AUX_IN"
      },
      {
        "netclass": "Clocks_100Ohm",
        "pattern": "/Display Port/DP_AUX_N"
      },
      {
        "netclass": "Clocks_100Ohm",
        "pattern": "/Display Port/DP_AUX_OUT"
      },
      {
        "netclass": "Clocks_100Ohm",
        "pattern": "/Display Port/DP_AUX_P"
      },
      {
        "netclass": "Clocks_100Ohm",
        "pattern": "/Ethernet/TD_A_N"
      },
      {
        "netclass": "Clocks_100Ohm",
        "pattern": "/Ethernet/TD_A_P"
      },
      {
        "netclass": "Clocks_100Ohm",
        "pattern": "/Ethernet/TD_B_N"
      },
      {
        "netclass": "Clocks_100Ohm",
        "pattern": "/Ethernet/TD_B_P"
      },
      {
        "netclass": "Clocks_100Ohm",
        "pattern": "/Ethernet/TD_C_N"
      },
      {
        "netclass": "Clocks_100Ohm",
        "pattern": "/Ethernet/TD_C_P"
      },
      {
        "netclass": "Clocks_100Ohm",
        "pattern": "/Ethernet/TD_D_N"
      },
      {
        "netclass": "Clocks_100Ohm",
        "pattern": "/Ethernet/TD_D_P"
      },
      {
        "netclass": "Supply",
        "pattern": "/Power Supply/DC Input/DC_IN"
      },
      {
        "netclass": "Supply",
        "pattern": "/Power Supply/DC/DC conventers/DC_MAIN_BUS"
      },
      {
        "netclass": "Supply",
        "pattern": "/Power Supply/PoE/POE_12V"
      },
      {
        "netclass": "Supply",
        "pattern": "/Power Supply/PoE/VDD_POE_IN"
      },
      {
        "netclass": "Supply",
        "pattern": "/Power Supply/PoE/VSS_POE_IN"
      },
      {
        "netclass": "Supply",
        "pattern": "/Power Supply/Supply ORing/PD_VBUS"
      },
      {
        "netclass": "Supply",
        "pattern": "PL_1V2"
      },
      {
        "netclass": "Supply",
        "pattern": "PL_3V3"
      },
      {
        "netclass": "Supply",
        "pattern": "PS_1V0"
      },
      {
        "netclass": "Supply",
        "pattern": "PS_1V2"
      },
      {
        "netclass": "Supply",
        "pattern": "PS_1V8"
      },
      {
        "netclass": "Supply",
        "pattern": "PS_2V5"
      },
      {
        "netclass": "Supply",
        "pattern": "PS_3V3"
      },
      {
        "netclass": "Supply",
        "pattern": "SOM_5V0"
      },
      {
        "netclass": "impedance_ctrl",
        "pattern": "/Camera interface/CAM0_RST"
      },
      {
        "netclass": "impedance_ctrl",
        "pattern": "/Camera interface/CAM0_VSYNC"
      },
      {
        "netclass": "impedance_ctrl",
        "pattern": "/Camera interface/CAM1_VSYNC"
      },
      {
        "netclass": "impedance_ctrl",
        "pattern": "/Camera interface/CCI0_I2C_SCL_3V3"
      },
      {
        "netclass": "impedance_ctrl",
        "pattern": "/Camera interface/CCI0_I2C_SDA_3V3"
      },
      {
        "netclass": "impedance_ctrl",
        "pattern": "/Camera interface/CCI1_I2C_SCL_3V3"
      },
      {
        "netclass": "impedance_ctrl",
        "pattern": "/Camera interface/CCI1_I2C_SDA_3V3"
      },
      {
        "netclass": "impedance_ctrl",
        "pattern": "/Camera interface/HDA01"
      },
      {
        "netclass": "impedance_ctrl",
        "pattern": "/Camera interface/HPA00_CC_N"
      },
      {
        "netclass": "impedance_ctrl",
        "pattern": "/Camera interface/HPA00_CC_P"
      },
      {
        "netclass": "impedance_ctrl",
        "pattern": "/Camera interface/HPA01_N"
      },
      {
        "netclass": "impedance_ctrl",
        "pattern": "/Camera interface/HPA01_P"
      },
      {
        "netclass": "impedance_ctrl",
        "pattern": "/Camera interface/HPA02_N"
      },
      {
        "netclass": "impedance_ctrl",
        "pattern": "/Camera interface/HPA02_P"
      },
      {
        "netclass": "impedance_ctrl",
        "pattern": "/Camera interface/HPA03_N"
      },
      {
        "netclass": "impedance_ctrl",
        "pattern": "/Camera interface/HPA03_P"
      },
      {
        "netclass": "impedance_ctrl",
        "pattern": "/Camera interface/HPA04_N"
      },
      {
        "netclass": "impedance_ctrl",
        "pattern": "/Camera interface/HPA04_P"
      },
      {
        "netclass": "impedance_ctrl",
        "pattern": "/Camera interface/HPA05_CC_N"
      },
      {
        "netclass": "impedance_ctrl",
        "pattern": "/Camera interface/HPA05_CC_P"
      },
      {
        "netclass": "impedance_ctrl",
        "pattern": "/Camera interface/HPA06_N"
      },
      {
        "netclass": "impedance_ctrl",
        "pattern": "/Camera interface/HPA06_P"
      },
      {
        "netclass": "impedance_ctrl",
        "pattern": "/Camera interface/HPA07_N"
      },
      {
        "netclass": "impedance_ctrl",
        "pattern": "/Camera interface/HPA07_P"
      },
      {
        "netclass": "impedance_ctrl",
        "pattern": "/Camera interface/HPA08_N"
      },
      {
        "netclass": "impedance_ctrl",
        "pattern": "/Camera interface/HPA08_P"
      },
      {
        "netclass": "impedance_ctrl",
        "pattern": "/Camera interface/HPA09_N"
      },
      {
        "netclass": "impedance_ctrl",
        "pattern": "/Camera interface/HPA09_P"
      },
      {
        "netclass": "impedance_ctrl",
        "pattern": "/Clock distribution/PS_CLK_EN"
      },
      {
        "netclass": "impedance_ctrl",
        "pattern": "/Clock distribution/~{M2_CLKREQ}"
      },
      {
        "netclass": "impedance_ctrl",
        "pattern": "/Debug and JTAG/CONN_GND"
      },
      {
        "netclass": "impedance_ctrl",
        "pattern": "/Debug and JTAG/EECLK"
      },
      {
        "netclass": "impedance_ctrl",
        "pattern": "/Debug and JTAG/EECS"
      },
      {
        "netclass": "impedance_ctrl",
        "pattern": "/Debug and JTAG/EEDATA"
      },
      {
        "netclass": "impedance_ctrl",
        "pattern": "/Debug and JTAG/FTDI_EEPROM_WC"
      },
      {
        "netclass": "impedance_ctrl",
        "pattern": "/Debug and JTAG/FTDI_TCK"
      },
      {
        "netclass": "impedance_ctrl",
        "pattern": "/Debug and JTAG/FTDI_TDI"
      },
      {
        "netclass": "impedance_ctrl",
        "pattern": "/Debug and JTAG/FTDI_TDO"
      },
      {
        "netclass": "impedance_ctrl",
        "pattern": "/Debug and JTAG/FTDI_TMS"
      },
      {
        "netclass": "impedance_ctrl",
        "pattern": "/Debug and JTAG/FTDI_UARTB_RXD"
      },
      {
        "netclass": "impedance_ctrl",
        "pattern": "/Debug and JTAG/FTDI_UARTB_TXD"
      },
      {
        "netclass": "impedance_ctrl",
        "pattern": "/Debug and JTAG/JTAG_TCK_C2M"
      },
      {
        "netclass": "impedance_ctrl",
        "pattern": "/Debug and JTAG/JTAG_TDI_C2M"
      },
      {
        "netclass": "impedance_ctrl",
        "pattern": "/Debug and JTAG/JTAG_TDO_M2C"
      },
      {
        "netclass": "impedance_ctrl",
        "pattern": "/Debug and JTAG/JTAG_TMS_C2M"
      },
      {
        "netclass": "impedance_ctrl",
        "pattern": "/Debug and JTAG/JTAG_VCCO_ON"
      },
      {
        "netclass": "impedance_ctrl",
        "pattern": "/Debug and JTAG/MIO36"
      },
      {
        "netclass": "impedance_ctrl",
        "pattern": "/Debug and JTAG/MIO37"
      },
      {
        "netclass": "impedance_ctrl",
        "pattern": "/Debug and JTAG/PD1_SVBUS"
      },
      {
        "netclass": "impedance_ctrl",
        "pattern": "/Debug and JTAG/PD_3V3"
      },
      {
        "netclass": "impedance_ctrl",
        "pattern": "/Debug and JTAG/PD_EN"
      },
      {
        "netclass": "impedance_ctrl",
        "pattern": "/Debug and JTAG/USBB_N"
      },
      {
        "netclass": "impedance_ctrl",
        "pattern": "/Debug and JTAG/USBB_P"
      },
      {
        "netclass": "impedance_ctrl",
        "pattern": "/Debug and JTAG/USBC_N"
      },
      {
        "netclass": "impedance_ctrl",
        "pattern": "/Debug and JTAG/USBC_P"
      },
      {
        "netclass": "impedance_ctrl",
        "pattern": "/Debug and JTAG/USB_1V2"
      },
      {
        "netclass": "impedance_ctrl",
        "pattern": "/Debug and JTAG/USB_3V3"
      },
      {
        "netclass": "impedance_ctrl",
        "pattern": "/Debug and JTAG/USB_N"
      },
      {
        "netclass": "impedance_ctrl",
        "pattern": "/Debug and JTAG/USB_P"
      },
      {
        "netclass": "impedance_ctrl",
        "pattern": "/Debug and JTAG/VCC_PD"
      },
      {
        "netclass": "impedance_ctrl",
        "pattern": "/Debug and JTAG/VCC_USB"
      },
      {
        "netclass": "impedance_ctrl",
        "pattern": "/Debug and JTAG/VREGIN"
      },
      {
        "netclass": "impedance_ctrl",
        "pattern": "/Debug and JTAG/XIN"
      },
      {
        "netclass": "impedance_ctrl",
        "pattern": "/Debug and JTAG/XOUT"
      },
      {
        "netclass": "impedance_ctrl",
        "pattern": "/Debug and JTAG/~{EEPROM_WC}"
      },
      {
        "netclass": "impedance_ctrl",
        "pattern": "/Debug and JTAG/~{FTDI_LS_OE}"
      },
      {
        "netclass": "impedance_ctrl",
        "pattern": "/Debug and JTAG/~{FTDI_PS_POR}"
      },
      {
        "netclass": "impedance_ctrl",
        "pattern": "/Debug and JTAG/~{FTDI_PS_SRST}"
      },
      {
        "netclass": "impedance_ctrl",
        "pattern": "/Debug and JTAG/~{FTDI_PWREN}"
      },
      {
        "netclass": "impedance_ctrl",
        "pattern": "/Debug and JTAG/~{LS_OE}"
      },
      {
        "netclass": "impedance_ctrl",
        "pattern": "/Debug and JTAG/~{PS_POR}"
      },
      {
        "netclass": "impedance_ctrl",
        "pattern": "/Debug and JTAG/~{PS_SRST_C2M}"
      },
      {
        "netclass": "impedance_ctrl",
        "pattern": "/Display Port/DP_HPD"
      },
      {
        "netclass": "impedance_ctrl",
        "pattern": "/Display Port/DP_OE"
      },
      {
        "netclass": "impedance_ctrl",
        "pattern": "/Display Port/GTR_DP0_M2C_C_N"
      },
      {
        "netclass": "impedance_ctrl",
        "pattern": "/Display Port/GTR_DP0_M2C_C_P"
      },
      {
        "netclass": "impedance_ctrl",
        "pattern": "/Display Port/GTR_DP0_M2C_N"
      },
      {
        "netclass": "impedance_ctrl",
        "pattern": "/Display Port/GTR_DP0_M2C_P"
      },
      {
        "netclass": "impedance_ctrl",
        "pattern": "/Display Port/GTR_DP1_M2C_C_N"
      },
      {
        "netclass": "impedance_ctrl",
        "pattern": "/Display Port/GTR_DP1_M2C_C_P"
      },
      {
        "netclass": "impedance_ctrl",
        "pattern": "/Display Port/GTR_DP1_M2C_N"
      },
      {
        "netclass": "impedance_ctrl",
        "pattern": "/Display Port/GTR_DP1_M2C_P"
      },
      {
        "netclass": "impedance_ctrl",
        "pattern": "/Display Port/MIO27"
      },
      {
        "netclass": "impedance_ctrl",
        "pattern": "/Display Port/MIO28"
      },
      {
        "netclass": "impedance_ctrl",
        "pattern": "/Display Port/MIO29"
      },
      {
        "netclass": "impedance_ctrl",
        "pattern": "/Display Port/MIO30"
      },
      {
        "netclass": "impedance_ctrl",
        "pattern": "/Ethernet/LED2"
      },
      {
        "netclass": "impedance_ctrl",
        "pattern": "/Ethernet/MIO64"
      },
      {
        "netclass": "impedance_ctrl",
        "pattern": "/Ethernet/MIO65"
      },
      {
        "netclass": "impedance_ctrl",
        "pattern": "/Ethernet/MIO66"
      },
      {
        "netclass": "impedance_ctrl",
        "pattern": "/Ethernet/MIO67"
      },
      {
        "netclass": "impedance_ctrl",
        "pattern": "/Ethernet/MIO68"
      },
      {
        "netclass": "impedance_ctrl",
        "pattern": "/Ethernet/MIO69"
      },
      {
        "netclass": "impedance_ctrl",
        "pattern": "/Ethernet/MIO70"
      },
      {
        "netclass": "impedance_ctrl",
        "pattern": "/Ethernet/MIO71"
      },
      {
        "netclass": "impedance_ctrl",
        "pattern": "/Ethernet/MIO72"
      },
      {
        "netclass": "impedance_ctrl",
        "pattern": "/Ethernet/MIO73"
      },
      {
        "netclass": "impedance_ctrl",
        "pattern": "/Ethernet/MIO74"
      },
      {
        "netclass": "impedance_ctrl",
        "pattern": "/Ethernet/MIO75"
      },
      {
        "netclass": "impedance_ctrl",
        "pattern": "/Ethernet/MIO76"
      },
      {
        "netclass": "impedance_ctrl",
        "pattern": "/Ethernet/MIO77"
      },
      {
        "netclass": "impedance_ctrl",
        "pattern": "/Ethernet/POE_VC1"
      },
      {
        "netclass": "impedance_ctrl",
        "pattern": "/Ethernet/POE_VC2"
      },
      {
        "netclass": "impedance_ctrl",
        "pattern": "/Ethernet/POE_VC3"
      },
      {
        "netclass": "impedance_ctrl",
        "pattern": "/Ethernet/POE_VC4"
      },
      {
        "netclass": "impedance_ctrl",
        "pattern": "/Ethernet/~{ETH_RESET}"
      },
      {
        "netclass": "impedance_ctrl",
        "pattern": "/I2C /I2C_SCK_3V3"
      },
      {
        "netclass": "impedance_ctrl",
        "pattern": "/I2C /I2C_SDA_3V3"
      },
      {
        "netclass": "impedance_ctrl",
        "pattern": "/I2C /MIO24_I2C_SCK"
      },
      {
        "netclass": "impedance_ctrl",
        "pattern": "/PCIE M2 key E /GTR_DP3_C2M_N"
      },
      {
        "netclass": "impedance_ctrl",
        "pattern": "/PCIE M2 key E /GTR_DP3_C2M_P"
      },
      {
        "netclass": "impedance_ctrl",
        "pattern": "/PCIE M2 key E /GTR_DP3_M2C_C_N"
      },
      {
        "netclass": "impedance_ctrl",
        "pattern": "/PCIE M2 key E /GTR_DP3_M2C_C_P"
      },
      {
        "netclass": "impedance_ctrl",
        "pattern": "/PCIE M2 key E /GTR_DP3_M2C_N"
      },
      {
        "netclass": "impedance_ctrl",
        "pattern": "/PCIE M2 key E /GTR_DP3_M2C_P"
      },
      {
        "netclass": "impedance_ctrl",
        "pattern": "/PCIE M2 key E /M2_USB_N"
      },
      {
        "netclass": "impedance_ctrl",
        "pattern": "/PCIE M2 key E /M2_USB_P"
      },
      {
        "netclass": "impedance_ctrl",
        "pattern": "/PCIE M2 key E /~{M2_PERST}"
      },
      {
        "netclass": "impedance_ctrl",
        "pattern": "/PCIE M2 key E /~{M2_PEWAKE}"
      },
      {
        "netclass": "impedance_ctrl",
        "pattern": "/PMOD/HDA11"
      },
      {
        "netclass": "impedance_ctrl",
        "pattern": "/PMOD/HDA12"
      },
      {
        "netclass": "impedance_ctrl",
        "pattern": "/PMOD/HDA13"
      },
      {
        "netclass": "impedance_ctrl",
        "pattern": "/PMOD/HDA14"
      },
      {
        "netclass": "impedance_ctrl",
        "pattern": "/PMOD/HDA15"
      },
      {
        "netclass": "impedance_ctrl",
        "pattern": "/PMOD/HDA16_CC"
      },
      {
        "netclass": "impedance_ctrl",
        "pattern": "/PMOD/HDA17"
      },
      {
        "netclass": "impedance_ctrl",
        "pattern": "/PMOD/HDA18"
      },
      {
        "netclass": "impedance_ctrl",
        "pattern": "/Power Supply/DC/DC conventers/SW_PS_1V0"
      },
      {
        "netclass": "impedance_ctrl",
        "pattern": "/Power Supply/PoE/POE_ACTIVE"
      },
      {
        "netclass": "impedance_ctrl",
        "pattern": "/Power Supply/USB-C socket/USBC_TVS_CC1"
      },
      {
        "netclass": "impedance_ctrl",
        "pattern": "/Power Supply/USB-C socket/USBC_TVS_CC2"
      },
      {
        "netclass": "impedance_ctrl",
        "pattern": "/Power Supply/USB-C socket/USBC_TVS_N"
      },
      {
        "netclass": "impedance_ctrl",
        "pattern": "/Power Supply/USB-C socket/USBC_TVS_P"
      },
      {
        "netclass": "impedance_ctrl",
        "pattern": "/Power Supply/VCCOEN_PL_M2C"
      },
      {
        "netclass": "impedance_ctrl",
        "pattern": "/Power Supply/VCCOEN_PS_M2C"
      },
      {
        "netclass": "impedance_ctrl",
        "pattern": "/Reset logic/HDA02"
      },
      {
        "netclass": "impedance_ctrl",
        "pattern": "/Reset logic/MIO38"
      },
      {
        "netclass": "impedance_ctrl",
        "pattern": "/Reset logic/MIO41"
      },
      {
        "netclass": "impedance_ctrl",
        "pattern": "/Reset logic/MIO43"
      },
      {
        "netclass": "impedance_ctrl",
        "pattern": "/Reset logic/MIO44"
      },
      {
        "netclass": "impedance_ctrl",
        "pattern": "/Reset logic/PL_RST"
      },
      {
        "netclass": "impedance_ctrl",
        "pattern": "/Reset logic/PS_RST"
      },
      {
        "netclass": "impedance_ctrl",
        "pattern": "/Reset logic/~{SD_CARD_RESET}"
      },
      {
        "netclass": "impedance_ctrl",
        "pattern": "/Reset logic/~{USB_HUB_RESET}"
      },
      {
        "netclass": "impedance_ctrl",
        "pattern": "/Reset logic/~{USB_PHY_RESET}"
      },
      {
        "netclass": "impedance_ctrl",
        "pattern": "/SD 3.0 card/MIO39"
      },
      {
        "netclass": "impedance_ctrl",
        "pattern": "/SD 3.0 card/MIO45"
      },
      {
        "netclass": "impedance_ctrl",
        "pattern": "/SD 3.0 card/MIO46"
      },
      {
        "netclass": "impedance_ctrl",
        "pattern": "/SD 3.0 card/MIO47"
      },
      {
        "netclass": "impedance_ctrl",
        "pattern": "/SD 3.0 card/MIO48"
      },
      {
        "netclass": "impedance_ctrl",
        "pattern": "/SD 3.0 card/MIO49"
      },
      {
        "netclass": "impedance_ctrl",
        "pattern": "/SD 3.0 card/MIO50"
      },
      {
        "netclass": "impedance_ctrl",
        "pattern": "/SD 3.0 card/MIO51"
      },
      {
        "netclass": "impedance_ctrl",
        "pattern": "/SD 3.0 card/VCCB"
      },
      {
        "netclass": "impedance_ctrl",
        "pattern": "/USB/GTR_DP2_C2M_C_N"
      },
      {
        "netclass": "impedance_ctrl",
        "pattern": "/USB/GTR_DP2_C2M_C_P"
      },
      {
        "netclass": "impedance_ctrl",
        "pattern": "/USB/GTR_DP2_C2M_N"
      },
      {
        "netclass": "impedance_ctrl",
        "pattern": "/USB/GTR_DP2_C2M_P"
      },
      {
        "netclass": "impedance_ctrl",
        "pattern": "/USB/GTR_DP2_M2C_C_N"
      },
      {
        "netclass": "impedance_ctrl",
        "pattern": "/USB/GTR_DP2_M2C_C_P"
      },
      {
        "netclass": "impedance_ctrl",
        "pattern": "/USB/GTR_DP2_M2C_N"
      },
      {
        "netclass": "impedance_ctrl",
        "pattern": "/USB/GTR_DP2_M2C_P"
      },
      {
        "netclass": "impedance_ctrl",
        "pattern": "/USB/MIO52"
      },
      {
        "netclass": "impedance_ctrl",
        "pattern": "/USB/MIO53"
      },
      {
        "netclass": "impedance_ctrl",
        "pattern": "/USB/MIO54"
      },
      {
        "netclass": "impedance_ctrl",
        "pattern": "/USB/MIO55"
      },
      {
        "netclass": "impedance_ctrl",
        "pattern": "/USB/MIO56"
      },
      {
        "netclass": "impedance_ctrl",
        "pattern": "/USB/MIO57"
      },
      {
        "netclass": "impedance_ctrl",
        "pattern": "/USB/MIO58"
      },
      {
        "netclass": "impedance_ctrl",
        "pattern": "/USB/MIO59"
      },
      {
        "netclass": "impedance_ctrl",
        "pattern": "/USB/MIO60"
      },
      {
        "netclass": "impedance_ctrl",
        "pattern": "/USB/MIO61"
      },
      {
        "netclass": "impedance_ctrl",
        "pattern": "/USB/MIO62"
      },
      {
        "netclass": "impedance_ctrl",
        "pattern": "/USB/MIO63"
      },
      {
        "netclass": "impedance_ctrl",
        "pattern": "/USB/USB1_N"
      },
      {
        "netclass": "impedance_ctrl",
        "pattern": "/USB/USB1_P"
      },
      {
        "netclass": "impedance_ctrl",
        "pattern": "/USB/USB1_RX_N"
      },
      {
        "netclass": "impedance_ctrl",
        "pattern": "/USB/USB1_RX_P"
      },
      {
        "netclass": "impedance_ctrl",
        "pattern": "/USB/USB1_TVS_N"
      },
      {
        "netclass": "impedance_ctrl",
        "pattern": "/USB/USB1_TVS_P"
      },
      {
        "netclass": "impedance_ctrl",
        "pattern": "/USB/USB1_TX_C_N"
      },
      {
        "netclass": "impedance_ctrl",
        "pattern": "/USB/USB1_TX_C_P"
      },
      {
        "netclass": "impedance_ctrl",
        "pattern": "/USB/USB1_TX_N"
      },
      {
        "netclass": "impedance_ctrl",
        "pattern": "/USB/USB1_TX_P"
      },
      {
        "netclass": "impedance_ctrl",
        "pattern": "/USB/USB1_VBUS"
      },
      {
        "netclass": "impedance_ctrl",
        "pattern": "/USB/USB2_N"
      },
      {
        "netclass": "impedance_ctrl",
        "pattern": "/USB/USB2_P"
      },
      {
        "netclass": "impedance_ctrl",
        "pattern": "/USB/USB2_PHY_N"
      },
      {
        "netclass": "impedance_ctrl",
        "pattern": "/USB/USB2_PHY_P"
      },
      {
        "netclass": "impedance_ctrl",
        "pattern": "/USB/USB2_REFCLK"
      },
      {
        "netclass": "impedance_ctrl",
        "pattern": "/USB/USB2_RX_N"
      },
      {
        "netclass": "impedance_ctrl",
        "pattern": "/USB/USB2_RX_P"
      },
      {
        "netclass": "impedance_ctrl",
        "pattern": "/USB/USB2_TVS_N"
      },
      {
        "netclass": "impedance_ctrl",
        "pattern": "/USB/USB2_TVS_P"
      },
      {
        "netclass": "impedance_ctrl",
        "pattern": "/USB/USB2_TX_C_N"
      },
      {
        "netclass": "impedance_ctrl",
        "pattern": "/USB/USB2_TX_C_P"
      },
      {
        "netclass": "impedance_ctrl",
        "pattern": "/USB/USB2_TX_N"
      },
      {
        "netclass": "impedance_ctrl",
        "pattern": "/USB/USB2_TX_P"
      },
      {
        "netclass": "impedance_ctrl",
        "pattern": "/USB/USB2_VBUS"
      },
      {
        "netclass": "impedance_ctrl",
        "pattern": "/USB/USB3_N"
      },
      {
        "netclass": "impedance_ctrl",
        "pattern": "/USB/USB3_P"
      },
      {
        "netclass": "impedance_ctrl",
        "pattern": "/USB/USB3_RX_N"
      },
      {
        "netclass": "impedance_ctrl",
        "pattern": "/USB/USB3_RX_P"
      },
      {
        "netclass": "impedance_ctrl",
        "pattern": "/USB/USB3_TVS_N"
      },
      {
        "netclass": "impedance_ctrl",
        "pattern": "/USB/USB3_TVS_P"
      },
      {
        "netclass": "impedance_ctrl",
        "pattern": "/USB/USB3_TX_C_N"
      },
      {
        "netclass": "impedance_ctrl",
        "pattern": "/USB/USB3_TX_C_P"
      },
      {
        "netclass": "impedance_ctrl",
        "pattern": "/USB/USB3_TX_N"
      },
      {
        "netclass": "impedance_ctrl",
        "pattern": "/USB/USB3_TX_P"
      },
      {
        "netclass": "impedance_ctrl",
        "pattern": "/USB/USB3_VBUS"
      },
      {
        "netclass": "impedance_ctrl",
        "pattern": "/USB/USB4_N"
      },
      {
        "netclass": "impedance_ctrl",
        "pattern": "/USB/USB4_P"
      },
      {
        "netclass": "impedance_ctrl",
        "pattern": "/USB/USB4_RX_N"
      },
      {
        "netclass": "impedance_ctrl",
        "pattern": "/USB/USB4_RX_P"
      },
      {
        "netclass": "impedance_ctrl",
        "pattern": "/USB/USB4_TVS_N"
      },
      {
        "netclass": "impedance_ctrl",
        "pattern": "/USB/USB4_TVS_P"
      },
      {
        "netclass": "impedance_ctrl",
        "pattern": "/USB/USB4_TX_C_N"
      },
      {
        "netclass": "impedance_ctrl",
        "pattern": "/USB/USB4_TX_C_P"
      },
      {
        "netclass": "impedance_ctrl",
        "pattern": "/USB/USB4_TX_N"
      },
      {
        "netclass": "impedance_ctrl",
        "pattern": "/USB/USB4_TX_P"
      },
      {
        "netclass": "impedance_ctrl",
        "pattern": "/USB/USB4_VBUS"
      },
      {
        "netclass": "impedance_ctrl",
        "pattern": "/Xilinx K26 SOM/HDA20"
      },
      {
        "netclass": "impedance_ctrl",
        "pattern": "/Xilinx K26 SOM/MODE0_C2M"
      },
      {
        "netclass": "impedance_ctrl",
        "pattern": "/Xilinx K26 SOM/MODE1_C2M"
      },
      {
        "netclass": "impedance_ctrl",
        "pattern": "/Xilinx K26 SOM/MODE2_C2M"
      },
      {
        "netclass": "impedance_ctrl",
        "pattern": "/Xilinx K26 SOM/MODE3_C2M"
      },
      {
        "netclass": "impedance_ctrl",
        "pattern": "GND"
      },
      {
        "netclass": "impedance_ctrl",
        "pattern": "GNDD"
      },
      {
        "netclass": "impedance_ctrl",
        "pattern": "Net-(D14-Pad1)"
      },
      {
        "netclass": "impedance_ctrl",
        "pattern": "Net-(D15-Pad1)"
      },
      {
        "netclass": "impedance_ctrl",
        "pattern": "Net-(D16-Pad1)"
      },
      {
        "netclass": "impedance_ctrl",
        "pattern": "Net-(D17-Pad1)"
      },
      {
        "netclass": "impedance_ctrl",
        "pattern": "Net-(D18-Pad1)"
      },
      {
        "netclass": "impedance_ctrl",
        "pattern": "Net-(D18-Pad2)"
      },
      {
        "netclass": "impedance_ctrl",
        "pattern": "Net-(D19-Pad1)"
      },
      {
        "netclass": "impedance_ctrl",
        "pattern": "Net-(D20-Pad1)"
      },
      {
        "netclass": "impedance_ctrl",
        "pattern": "Net-(FB1-Pad2)"
      },
      {
        "netclass": "impedance_ctrl",
        "pattern": "Net-(FB2-Pad2)"
      },
      {
        "netclass": "impedance_ctrl",
        "pattern": "Net-(J1-Pad13)"
      },
      {
        "netclass": "impedance_ctrl",
        "pattern": "Net-(J1-Pad14)"
      },
      {
        "netclass": "impedance_ctrl",
        "pattern": "Net-(J1-Pad19)"
      },
      {
        "netclass": "impedance_ctrl",
        "pattern": "Net-(J5-Pad15)"
      },
      {
        "netclass": "impedance_ctrl",
        "pattern": "Net-(J5-Pad16)"
      },
      {
        "netclass": "impedance_ctrl",
        "pattern": "Net-(J5-Pad17)"
      },
      {
        "netclass": "impedance_ctrl",
        "pattern": "Net-(J5-Pad18)"
      },
      {
        "netclass": "impedance_ctrl",
        "pattern": "Net-(Q1-Pad3)"
      },
      {
        "netclass": "impedance_ctrl",
        "pattern": "Net-(Q3-Pad3)"
      },
      {
        "netclass": "impedance_ctrl",
        "pattern": "Net-(R42-Pad2)"
      },
      {
        "netclass": "impedance_ctrl",
        "pattern": "Net-(R49-Pad2)"
      }
    ]
  },
  "pcbnew": {
    "last_paths": {
      "gencad": "",
      "idf": "",
      "netlist": "kria-k26-devboard.net",
      "specctra_dsn": "",
      "step": "",
      "vrml": ""
    },
    "page_layout_descr_file": ""
  },
  "schematic": {
    "annotate_start_num": 0,
    "drawing": {
      "dashed_lines_dash_length_ratio": 12.0,
      "dashed_lines_gap_length_ratio": 3.0,
      "default_line_thickness": 6.0,
      "default_text_size": 50.0,
      "field_names": [],
      "intersheets_ref_own_page": false,
      "intersheets_ref_prefix": "",
      "intersheets_ref_short": false,
      "intersheets_ref_show": false,
      "intersheets_ref_suffix": "",
      "junction_size_choice": 3,
      "label_size_ratio": 0.25,
      "pin_symbol_size": 0.0,
      "text_offset_ratio": 0.08
    },
    "legacy_lib_dir": "",
    "legacy_lib_list": [],
    "meta": {
      "version": 1
    },
    "net_format_name": "Pcbnew",
    "ngspice": {
      "fix_include_paths": true,
      "fix_passive_vals": false,
      "meta": {
        "version": 0
      },
      "model_mode": 0,
      "workbook_filename": ""
    },
    "page_layout_descr_file": "",
    "plot_directory": "./doc/",
    "spice_adjust_passive_values": false,
    "spice_current_sheet_as_root": false,
    "spice_external_command": "spice \"%I\"",
    "spice_model_current_sheet_as_root": true,
    "spice_save_all_currents": false,
    "spice_save_all_voltages": false,
    "subpart_first_id": 65,
    "subpart_id_separator": 0
  },
  "sheets": [
    [
      "",
      ""
    ],
    [
      "",
      "Power Supply"
    ],
    [
      "",
      "USB-C socket"
    ],
    [
      "",
      "DC Input"
    ],
    [
      "",
      "PoE"
    ],
    [
      "",
      "Supply ORing"
    ],
    [
      "",
      "DC/DC conventers"
    ],
    [
      "",
      "Debug and JTAG"
    ],
    [
      "",
      "Camera interface"
    ],
    [
      "",
      "Reset logic"
    ],
    [
      "",
      "Xilinx K26 SOM"
    ],
    [
      "",
      "Ethernet"
    ],
    [
      "",
      "USB"
    ],
    [
      "",
      "SD 3.0 card"
    ],
    [
      "",
      "Display Port"
    ],
    [
      "",
      "PCIE M2 key E "
    ],
    [
      "",
      "Clock distribution"
    ],
    [
      "",
      "I2C "
    ],
    [
      "",
      "PMOD"
    ]
  ],
  "text_variables": {}
}
